# TIMECARD (Time Appliance Project (Time Card)) — schematic netlist excerpt (pin names and nets, part order shuffled) for the footprints in the layout excerpt that follows; sources: Cadence DE-HDL packaged netlist, KiCad conversion of R4006-B0001-02_R01.brd

L34  FERRITEBEAD  120OHM 25%  pkg SMC_0603R_H030  page 14 : \1\ = XP1R0V_FPGA_MGTAVCC ; \2\ = XP1R0V_FPGA

(kicad_pcb
	(version 20260206)
	(generator "pcbnew")
	(generator_version "10.0")
	(general
		(thickness 1.6)
		(legacy_teardrops no)
	)
	(paper "A4")
	(title_block
		(title "timecard-production-celestica-r4006 — R4006-B0001-02_R01.brd")
		(comment 1 "Time Appliance Project (Time Card) / footprints 102-102 of 1113")
	)
	(layers
		(0 "F.Cu" signal "TOP")
		(4 "In1.Cu" signal "L02_GND1")
		(6 "In2.Cu" signal "L03_SIG1")
		(8 "In3.Cu" signal "L04_GND2")
		(10 "In4.Cu" signal "L05_VCC1")
		(12 "In5.Cu" signal "L06_VCC2")
		(14 "In6.Cu" signal "L07_GND3")
		(16 "In7.Cu" signal "L08_SIG2")
		(18 "In8.Cu" signal "L09_GND4")
		(2 "B.Cu" signal "BOTTOM")
		(9 "F.Adhes" user "F.Adhesive")
		(11 "B.Adhes" user "B.Adhesive")
		(13 "F.Paste" user "Package Geometry/Pastemask Top")
		(15 "B.Paste" user "Package Geometry/Pastemask Bottom")
		(5 "F.SilkS" user "Ref Des/Silkscreen Top")
		(7 "B.SilkS" user "Ref Des/Silkscreen Bottom")
		(1 "F.Mask" user "Board Geometry/Soldermask Top")
		(3 "B.Mask" user "Board Geometry/Soldermask Bottom")
		(17 "Dwgs.User" user "User.Drawings")
		(19 "Cmts.User" user "User.Comments")
		(21 "Eco1.User" user "User.Eco1")
		(23 "Eco2.User" user "User.Eco2")
		(25 "Edge.Cuts" user "Board Geometry/Outline")
		(27 "Margin" user)
		(31 "F.CrtYd" user "Package Geometry/Place Bound Top")
		(29 "B.CrtYd" user "Package Geometry/Place Bound Bottom")
		(35 "F.Fab" user "Ref Des/Assembly Top")
		(33 "B.Fab" user "Ref Des/Assembly Bottom")
	)
	(footprint ""
		(layer "F.Cu")
		(at 92.583 -37.338 180)
		(property "Reference" "L34"
			(at 1.2065 -1.43637 0)
			(unlocked yes)
			(layer "F.SilkS")
			(effects
				(font
					(size 0.7874 0.5842)
					(thickness 0.1524)
				)
				(justify left)
			)
		)
		(property "Value" "VAL*"
			(at -0.9398 3.70967 180)
			(unlocked yes)
			(layer "F.Fab")
			(hide yes)
			(effects
				(font
					(size 0.7874 0.5842)
					(thickness 0.1524)
				)
				(justify left)
			)
		)
		(property "Device Type" "FERRITEBEAD-G191-10100-01,120OA"
			(at -0.9906 1.22047 180)
			(unlocked yes)
			(layer "F.Fab")
			(hide yes)
			(effects
				(font
					(size 0.7874 0.5842)
					(thickness 0.1524)
				)
				(justify left)
			)
		)
		(property "User Part Number" "PARTNUM*"
			(at -2.54 2.46507 180)
			(unlocked yes)
			(layer "Cmts.User")
			(hide yes)
			(effects
				(font
					(size 0.7874 0.5842)
					(thickness 0.1524)
				)
				(justify left)
			)
		)
		(property "Tolerance" "TOL*"
			(at -0.9906 5.00507 180)
			(unlocked yes)
			(layer "Cmts.User")
			(hide yes)
			(effects
				(font
					(size 0.7874 0.5842)
					(thickness 0.1524)
				)
				(justify left)
			)
		)
		(duplicate_pad_numbers_are_jumpers no)
		(fp_line
			(start 1.3208 0.7112)
			(end -1.3208 0.7112)
			(stroke
				(width 0.1)
				(type default)
			)
			(layer "F.SilkS")
		)
		(fp_line
			(start 1.3208 -0.7112)
			(end 1.3208 0.7112)
			(stroke
				(width 0.1)
				(type default)
			)
			(layer "F.SilkS")
		)
		(fp_line
			(start -1.3208 0.7112)
			(end -1.3208 -0.7112)
			(stroke
				(width 0.1)
				(type default)
			)
			(layer "F.SilkS")
		)
		(fp_line
			(start -1.3208 -0.7112)
			(end 1.3208 -0.7112)
			(stroke
				(width 0.1)
				(type default)
			)
			(layer "F.SilkS")
		)
		(fp_rect
			(start -1.3208 0.7112)
			(end 1.3208 -0.7112)
			(stroke
				(width 0)
				(type default)
			)
			(fill no)
			(layer "F.CrtYd")
		)
		(fp_line
			(start 0.8128 0.4572)
			(end -0.8128 0.4572)
			(stroke
				(width 0.1)
				(type default)
			)
			(layer "F.Fab")
		)
		(fp_line
			(start 0.8128 -0.4572)
			(end 0.8128 0.4572)
			(stroke
				(width 0.1)
				(type default)
			)
			(layer "F.Fab")
		)
		(fp_line
			(start -0.8128 0.4572)
			(end -0.8128 -0.4572)
			(stroke
				(width 0.1)
				(type default)
			)
			(layer "F.Fab")
		)
		(fp_line
			(start -0.8128 -0.4572)
			(end 0.8128 -0.4572)
			(stroke
				(width 0.1)
				(type default)
			)
			(layer "F.Fab")
		)
		(pad "1" smd rect
			(at -0.6858 0 180)
			(size 0.762 0.8636)
			(layers "F.Cu" "F.Mask" "F.Paste")
			(net "XP1R0V_FPGA_MGTAVCC")
		)
		(pad "2" smd rect
			(at 0.6858 0 180)
			(size 0.762 0.8636)
			(layers "F.Cu" "F.Mask" "F.Paste")
			(net "XP1R0V_FPGA")
		)
		(zone
			(layer "F.Cu")
			(hatch none 0.5)
			(connect_pads
				(clearance 0)
			)
			(min_thickness 0.25)
			(keepout
				(tracks not_allowed)
				(vias allowed)
				(pads allowed)
				(copperpour not_allowed)
				(footprints allowed)
			)
			(placement
				(enabled no)
				(sheetname "")
			)
			(fill
				(thermal_gap 0.5)
				(thermal_bridge_width 0.5)
				(island_removal_mode 0)
			)
			(polygon
				(pts
					(xy 92.7354 -37.7952) (xy 92.4306 -37.7952) (xy 92.4306 -36.8808) (xy 92.7354 -36.8808)
				)
			)
		)
		(zone
			(layer "F.Cu")
			(hatch none 0.5)
			(connect_pads
				(clearance 0)
			)
			(min_thickness 0.25)
			(keepout
				(tracks allowed)
				(vias not_allowed)
				(pads allowed)
				(copperpour not_allowed)
				(footprints allowed)
			)
			(placement
				(enabled no)
				(sheetname "")
			)
			(fill
				(thermal_gap 0.5)
				(thermal_bridge_width 0.5)
				(island_removal_mode 0)
			)
			(polygon
				(pts
					(xy 92.7354 -37.7952) (xy 92.4306 -37.7952) (xy 92.4306 -36.8808) (xy 92.7354 -36.8808)
				)
			)
		)
	)
)
